(kicad_pcb
	(version 20260206)
	(generator "pcbnew")
	(generator_version "10.0")
	(general
		(thickness 1.6)
		(legacy_teardrops no)
	)
	(paper "A4")
	(title_block
		(title "Bryce Canyon_F.DPB_16315-1-OCP.brd")
		(comment 1 "Bryce Canyon / footprints 1887-1891 of 2223")
	)
	(layers
		(0 "F.Cu" signal "TOP")
		(4 "In1.Cu" signal "L2GND")
		(6 "In2.Cu" signal "L3")
		(8 "In3.Cu" signal "L4GND")
		(10 "In4.Cu" signal "L5")
		(12 "In5.Cu" signal "L6VCC")
		(14 "In6.Cu" signal "L7VCC")
		(16 "In7.Cu" signal "L8")
		(18 "In8.Cu" signal "L9GND")
		(20 "In9.Cu" signal "L10")
		(22 "In10.Cu" signal "L11GND")
		(2 "B.Cu" signal "BOTTOM")
		(9 "F.Adhes" user "F.Adhesive")
		(11 "B.Adhes" user "B.Adhesive")
		(13 "F.Paste" user "Package Geometry/Pastemask Top")
		(15 "B.Paste" user "Package Geometry/Pastemask Bottom")
		(5 "F.SilkS" user "Ref Des/Silkscreen Top")
		(7 "B.SilkS" user "Ref Des/Silkscreen Bottom")
		(1 "F.Mask" user "Board Geometry/Soldermask Top")
		(3 "B.Mask" user "Board Geometry/Soldermask Bottom")
		(17 "Dwgs.User" user "User.Drawings")
		(19 "Cmts.User" user "User.Comments")
		(21 "Eco1.User" user "User.Eco1")
		(23 "Eco2.User" user "User.Eco2")
		(25 "Edge.Cuts" user "Board Geometry/Outline")
		(27 "Margin" user)
		(31 "F.CrtYd" user "Package Geometry/Place Bound Top")
		(29 "B.CrtYd" user "Package Geometry/Place Bound Bottom")
		(35 "F.Fab" user "Ref Des/Assembly Top")
		(33 "B.Fab" user "Ref Des/Assembly Bottom")
	)
	(footprint ""
		(layer "F.Cu")
		(at 52.566824 -142.179548 90)
		(property "Reference" "C622"
			(at 0 0 90)
			(layer "F.SilkS")
			(hide yes)
			(effects
				(font
					(size 1.27 1.27)
				)
			)
		)
		(property "Value" "SCD1U16V2KX-3GP"
			(at 1.1811 -2.7051 90)
			(unlocked yes)
			(layer "F.Fab")
			(hide yes)
			(effects
				(font
					(size 1.016 1.016)
					(thickness 0.1524)
				)
			)
		)
		(property "Device Type" "C402H22"
			(at 1.1811 -4.2291 90)
			(unlocked yes)
			(layer "F.Fab")
			(hide yes)
			(effects
				(font
					(size 1.016 1.016)
					(thickness 0.1524)
				)
			)
		)
		(duplicate_pad_numbers_are_jumpers no)
		(fp_rect
			(start -0.4318 0.9525)
			(end 0.4318 -0.9525)
			(stroke
				(width 0)
				(type default)
			)
			(fill no)
			(layer "F.CrtYd")
		)
		(fp_rect
			(start -0.4318 0.9525)
			(end 0.4318 -0.9525)
			(stroke
				(width 0)
				(type default)
			)
			(fill no)
			(layer "F.Fab")
		)
		(pad "1" smd custom
			(at 0 -0.4445 90)
			(size 0.1524 0.1524)
			(layers "F.Cu" "F.Mask" "F.Paste")
			(net "P5V_B_VBST_RC")
			(options
				(clearance outline)
				(anchor circle)
			)
			(primitives
				(gr_poly
					(pts
						(arc
							(start 0.3048 -0.2032)
							(mid 0.275042 -0.275042)
							(end 0.2032 -0.3048)
						)
						(arc
							(start -0.2032 -0.3048)
							(mid -0.275042 -0.275042)
							(end -0.3048 -0.2032)
						)
						(arc
							(start -0.3048 0.2032)
							(mid -0.275042 0.275042)
							(end -0.2032 0.3048)
						)
						(arc
							(start 0.2032 0.3048)
							(mid 0.275042 0.275042)
							(end 0.3048 0.2032)
						)
					)
					(width 0)
					(fill yes)
				)
			)
		)
		(pad "2" smd custom
			(at 0 0.4445 90)
			(size 0.1524 0.1524)
			(layers "F.Cu" "F.Mask" "F.Paste")
			(net "P5V_B_LL")
			(options
				(clearance outline)
				(anchor circle)
			)
			(primitives
				(gr_poly
					(pts
						(arc
							(start 0.3048 -0.2032)
							(mid 0.275042 -0.275042)
							(end 0.2032 -0.3048)
						)
						(arc
							(start -0.2032 -0.3048)
							(mid -0.275042 -0.275042)
							(end -0.3048 -0.2032)
						)
						(arc
							(start -0.3048 0.2032)
							(mid -0.275042 0.275042)
							(end -0.2032 0.3048)
						)
						(arc
							(start 0.2032 0.3048)
							(mid 0.275042 0.275042)
							(end 0.3048 0.2032)
						)
					)
					(width 0)
					(fill yes)
				)
			)
		)
	)
	(footprint ""
		(layer "F.Cu")
		(at 118.585996 -301.287942)
		(property "Reference" "C83"
			(at 0 0 0)
			(layer "F.SilkS")
			(hide yes)
			(effects
				(font
					(size 1.27 1.27)
				)
			)
		)
		(property "Value" "SC4D7U25V5KX-1-GP"
			(at -0.0762 -6.1214 0)
			(unlocked yes)
			(layer "F.Fab")
			(hide yes)
			(effects
				(font
					(size 1.016 1.016)
					(thickness 0.1524)
				)
			)
		)
		(property "Device Type" "C805H58"
			(at -0.0762 -8.1534 0)
			(unlocked yes)
			(layer "F.Fab")
			(hide yes)
			(effects
				(font
					(size 1.016 1.016)
					(thickness 0.1524)
				)
			)
		)
		(duplicate_pad_numbers_are_jumpers no)
		(fp_line
			(start 0.635 0)
			(end -0.635 0)
			(stroke
				(width 0.508)
				(type default)
			)
			(layer "F.SilkS")
		)
		(fp_rect
			(start -0.9652 1.778)
			(end 0.9652 -1.778)
			(stroke
				(width 0)
				(type default)
			)
			(fill no)
			(layer "F.CrtYd")
		)
		(fp_poly
			(pts
				(xy -0.9652 -1.778) (xy 0.9652 -1.778) (xy 0.9652 1.778) (xy -0.9652 1.778)
			)
			(stroke
				(width 0)
				(type default)
			)
			(fill no)
			(layer "F.Fab")
		)
		(pad "1" smd rect
			(at 0 -0.9652)
			(size 1.397 1.143)
			(layers "F.Cu" "F.Mask" "F.Paste")
			(net "P12V_HDD3")
		)
		(pad "2" smd rect
			(at 0 0.9652)
			(size 1.397 1.143)
			(layers "F.Cu" "F.Mask" "F.Paste")
			(net "GND")
		)
	)
	(footprint ""
		(layer "F.Cu")
		(at 472.899994 -94.400116)
		(property "Reference" "FLED24"
			(at 0 0 0)
			(layer "F.SilkS")
			(hide yes)
			(effects
				(font
					(size 1.27 1.27)
				)
			)
		)
		(property "Value" "LED-BY-19-GP"
			(at -2.132076 1.414018 0)
			(unlocked yes)
			(layer "F.Fab")
			(hide yes)
			(effects
				(font
					(size 1.016 1.016)
					(thickness 0.1524)
				)
			)
		)
		(property "Device Type" "LED-1615-4PH26"
			(at -2.132076 -0.109982 0)
			(unlocked yes)
			(layer "F.Fab")
			(hide yes)
			(effects
				(font
					(size 1.016 1.016)
					(thickness 0.1524)
				)
			)
		)
		(duplicate_pad_numbers_are_jumpers no)
		(fp_line
			(start -1.2954 0.254)
			(end -1.2954 1.6002)
			(stroke
				(width 0.508)
				(type default)
			)
			(layer "F.SilkS")
		)
		(fp_line
			(start -1.2954 1.6002)
			(end 1.2954 1.6002)
			(stroke
				(width 0.508)
				(type default)
			)
			(layer "F.SilkS")
		)
		(fp_line
			(start -1.1176 -1.4224)
			(end 1.1176 -1.4224)
			(stroke
				(width 0.1524)
				(type default)
			)
			(layer "F.SilkS")
		)
		(fp_line
			(start -1.1176 1.4224)
			(end -1.1176 -1.4224)
			(stroke
				(width 0.1524)
				(type default)
			)
			(layer "F.SilkS")
		)
		(fp_line
			(start 1.1176 -1.4224)
			(end 1.1176 1.4224)
			(stroke
				(width 0.1524)
				(type default)
			)
			(layer "F.SilkS")
		)
		(fp_line
			(start 1.1176 1.4224)
			(end -1.1176 1.4224)
			(stroke
				(width 0.1524)
				(type default)
			)
			(layer "F.SilkS")
		)
		(fp_line
			(start 1.2954 1.6002)
			(end 1.2954 0.254)
			(stroke
				(width 0.508)
				(type default)
			)
			(layer "F.SilkS")
		)
		(fp_rect
			(start -0.7493 0.8001)
			(end 0.7493 -0.8001)
			(stroke
				(width 0)
				(type default)
			)
			(fill no)
			(layer "F.CrtYd")
		)
		(fp_poly
			(pts
				(xy -1.3716 1.6764) (xy -1.3716 -1.6764) (xy 1.3716 -1.6764) (xy 1.3716 0.0635) (xy 0.7493 0.0635)
				(xy 0.7493 -0.8001) (xy -0.7493 -0.8001) (xy -0.7493 0.8001) (xy 0.7493 0.8001) (xy 0.7493 0.0762)
				(xy 1.3716 0.0762) (xy 1.3716 1.6764)
			)
			(stroke
				(width 0)
				(type default)
			)
			(fill no)
			(layer "F.CrtYd")
		)
		(fp_rect
			(start -1.3716 1.6764)
			(end 1.3716 -1.6764)
			(stroke
				(width 0)
				(type default)
			)
			(fill no)
			(layer "F.Fab")
		)
		(pad "1" smd rect
			(at 0.50038 -0.73025)
			(size 0.7112 0.8636)
			(layers "F.Cu" "F.Mask" "F.Paste")
			(net "DRV_ACT_23")
		)
		(pad "2" smd rect
			(at -0.50038 -0.73025)
			(size 0.7112 0.8636)
			(layers "F.Cu" "F.Mask" "F.Paste")
			(net "FLT_HDD23")
		)
		(pad "3" smd rect
			(at 0.50038 0.73025)
			(size 0.7112 0.8636)
			(layers "F.Cu" "F.Mask" "F.Paste")
			(net "DRV_ACT_23_N")
		)
		(pad "4" smd rect
			(at -0.50038 0.73025)
			(size 0.7112 0.8636)
			(layers "F.Cu" "F.Mask" "F.Paste")
			(net "FLT_HDD23_N")
		)
	)
	(footprint ""
		(layer "F.Cu")
		(at 461.9879 -42.585894 180)
		(property "Reference" "R922"
			(at 0 0 180)
			(layer "F.SilkS")
			(hide yes)
			(effects
				(font
					(size 1.27 1.27)
				)
			)
		)
		(property "Value" "0R2J-2-GP"
			(at 0.064008 -3.993896 180)
			(unlocked yes)
			(layer "F.Fab")
			(hide yes)
			(effects
				(font
					(size 1.016 1.016)
					(thickness 0.1524)
				)
			)
		)
		(property "Device Type" "R402H16"
			(at 0.064008 -5.517896 180)
			(unlocked yes)
			(layer "F.Fab")
			(hide yes)
			(effects
				(font
					(size 1.016 1.016)
					(thickness 0.1524)
				)
			)
		)
		(duplicate_pad_numbers_are_jumpers no)
		(fp_line
			(start 0.508 -0.9398)
			(end -0.508 -0.9398)
			(stroke
				(width 0.1524)
				(type default)
			)
			(layer "F.SilkS")
		)
		(fp_line
			(start -0.508 -0.9398)
			(end -0.508 0.9398)
			(stroke
				(width 0.1524)
				(type default)
			)
			(layer "F.SilkS")
		)
		(fp_rect
			(start -0.508 0.9398)
			(end 0.508 -0.9398)
			(stroke
				(width 0)
				(type default)
			)
			(fill no)
			(layer "F.CrtYd")
		)
		(fp_rect
			(start -0.508 0.9398)
			(end 0.508 -0.9398)
			(stroke
				(width 0)
				(type default)
			)
			(fill no)
			(layer "F.Fab")
		)
		(pad "1" smd custom
			(at 0 -0.4445 180)
			(size 0.1397 0.1397)
			(layers "F.Cu" "F.Mask" "F.Paste")
			(net "DRIVE_A_34_PWR")
			(options
				(clearance outline)
				(anchor circle)
			)
			(primitives
				(gr_poly
					(pts
						(arc
							(start -0.1778 -0.2794)
							(mid -0.249642 -0.249642)
							(end -0.2794 -0.1778)
						)
						(arc
							(start -0.2794 0.1778)
							(mid -0.249642 0.249642)
							(end -0.1778 0.2794)
						)
						(arc
							(start 0.1778 0.2794)
							(mid 0.249642 0.249642)
							(end 0.2794 0.1778)
						)
						(arc
							(start 0.2794 -0.1778)
							(mid 0.249642 -0.249642)
							(end 0.1778 -0.2794)
						)
					)
					(width 0)
					(fill yes)
				)
			)
		)
		(pad "2" smd custom
			(at 0 0.4445 180)
			(size 0.1397 0.1397)
			(layers "F.Cu" "F.Mask" "F.Paste")
			(net "SW_PWR_R_HDD34")
			(options
				(clearance outline)
				(anchor circle)
			)
			(primitives
				(gr_poly
					(pts
						(arc
							(start -0.1778 -0.2794)
							(mid -0.249642 -0.249642)
							(end -0.2794 -0.1778)
						)
						(arc
							(start -0.2794 0.1778)
							(mid -0.249642 0.249642)
							(end -0.1778 0.2794)
						)
						(arc
							(start 0.1778 0.2794)
							(mid 0.249642 0.249642)
							(end 0.2794 0.1778)
						)
						(arc
							(start 0.2794 -0.1778)
							(mid 0.249642 -0.249642)
							(end 0.1778 -0.2794)
						)
					)
					(width 0)
					(fill yes)
				)
			)
		)
	)
	(footprint ""
		(layer "F.Cu")
		(at 271.251172 -5.69087 90)
		(property "Reference" "R995"
			(at 0 0 90)
			(layer "F.SilkS")
			(hide yes)
			(effects
				(font
					(size 1.27 1.27)
				)
			)
		)
		(property "Value" "100KR2F-L1-GP"
			(at 0.064008 -3.993896 90)
			(unlocked yes)
			(layer "F.Fab")
			(hide yes)
			(effects
				(font
					(size 1.016 1.016)
					(thickness 0.1524)
				)
			)
		)
		(property "Device Type" "R402H16"
			(at 0.064008 -5.517896 90)
			(unlocked yes)
			(layer "F.Fab")
			(hide yes)
			(effects
				(font
					(size 1.016 1.016)
					(thickness 0.1524)
				)
			)
		)
		(duplicate_pad_numbers_are_jumpers no)
		(fp_line
			(start 0.508 -0.9398)
			(end -0.508 -0.9398)
			(stroke
				(width 0.1524)
				(type default)
			)
			(layer "F.SilkS")
		)
		(fp_line
			(start -0.508 -0.9398)
			(end -0.508 0.9398)
			(stroke
				(width 0.1524)
				(type default)
			)
			(layer "F.SilkS")
		)
		(fp_rect
			(start -0.508 0.9398)
			(end 0.508 -0.9398)
			(stroke
				(width 0)
				(type default)
			)
			(fill no)
			(layer "F.CrtYd")
		)
		(fp_rect
			(start -0.508 0.9398)
			(end 0.508 -0.9398)
			(stroke
				(width 0)
				(type default)
			)
			(fill no)
			(layer "F.Fab")
		)
		(pad "1" smd custom
			(at 0 -0.4445 90)
			(size 0.1397 0.1397)
			(layers "F.Cu" "F.Mask" "F.Paste")
			(net "P3V3_STBY_B")
			(options
				(clearance outline)
				(anchor circle)
			)
			(primitives
				(gr_poly
					(pts
						(arc
							(start -0.1778 -0.2794)
							(mid -0.249642 -0.249642)
							(end -0.2794 -0.1778)
						)
						(arc
							(start -0.2794 0.1778)
							(mid -0.249642 0.249642)
							(end -0.1778 0.2794)
						)
						(arc
							(start 0.1778 0.2794)
							(mid 0.249642 0.249642)
							(end 0.2794 0.1778)
						)
						(arc
							(start 0.2794 -0.1778)
							(mid 0.249642 -0.249642)
							(end 0.1778 -0.2794)
						)
					)
					(width 0)
					(fill yes)
				)
			)
		)
		(pad "2" smd custom
			(at 0 0.4445 90)
			(size 0.1397 0.1397)
			(layers "F.Cu" "F.Mask" "F.Paste")
			(net "COMP_B_SEC_INS_N")
			(options
				(clearance outline)
				(anchor circle)
			)
			(primitives
				(gr_poly
					(pts
						(arc
							(start -0.1778 -0.2794)
							(mid -0.249642 -0.249642)
							(end -0.2794 -0.1778)
						)
						(arc
							(start -0.2794 0.1778)
							(mid -0.249642 0.249642)
							(end -0.1778 0.2794)
						)
						(arc
							(start 0.1778 0.2794)
							(mid 0.249642 0.249642)
							(end 0.2794 0.1778)
						)
						(arc
							(start 0.2794 -0.1778)
							(mid 0.249642 -0.249642)
							(end 0.1778 -0.2794)
						)
					)
					(width 0)
					(fill yes)
				)
			)
		)
	)
)
